FILE_TYPE=LIBRARY_PARTS;
primitive 'PXM1310B','PXM1310B_QFN';
  pin
    'BPWM1':
      PIN_NUMBER='(1)';
      OUTPUT_LOAD='(1.0,-1.0)';
    'DNC'<0>:
      PIN_NUMBER='(2)';
      PINUSE='NC';
      NO_LOAD_CHECK='Both';
      NO_IO_CHECK='Both';
      NO_ASSERT_CHECK='TRUE';
      NO_DIR_CHECK='TRUE';
      ALLOW_CONNECT='TRUE';
    'APWM3':
      PIN_NUMBER='(3)';
      OUTPUT_LOAD='(1.0,-1.0)';
    'APWM2':
      PIN_NUMBER='(4)';
      OUTPUT_LOAD='(1.0,-1.0)';
    'APWM1':
      PIN_NUMBER='(5)';
      OUTPUT_LOAD='(1.0,-1.0)';
    'SDA':
      PIN_NUMBER='(6)';
      BIDIRECTIONAL='TRUE';
      INPUT_LOAD='(-0.01,0.01)';
      OUTPUT_LOAD='(1.0,-1.0)';
    'SCL':
      PIN_NUMBER='(7)';
      BIDIRECTIONAL='TRUE';
      INPUT_LOAD='(-0.01,0.01)';
      OUTPUT_LOAD='(1.0,-1.0)';
    'RESET_N':
      PIN_NUMBER='(8)';
      INPUT_LOAD='(-0.01,0.01)';
    'AVRRDY':
      PIN_NUMBER='(9)';
      OUTPUT_LOAD='(1.0,-1.0)';
    'AVREN':
      PIN_NUMBER='(10)';
      INPUT_LOAD='(-0.01,0.01)';
    'VRHOT_N':
      PIN_NUMBER='(11)';
      OUTPUT_LOAD='(1.0,-1.0)';
    'PINALRT_N':
      PIN_NUMBER='(12)';
      OUTPUT_LOAD='(1.0,-1.0)';
    'MP0':
      PIN_NUMBER='(13)';
      BIDIRECTIONAL='TRUE';
      INPUT_LOAD='(-0.01,0.01)';
      OUTPUT_LOAD='(1.0,-1.0)';
    'MP1':
      PIN_NUMBER='(14)';
      BIDIRECTIONAL='TRUE';
      INPUT_LOAD='(-0.01,0.01)';
      OUTPUT_LOAD='(1.0,-1.0)';
    'VCLK':
      PIN_NUMBER='(15)';
      INPUT_LOAD='(-0.01,0.01)';
    'VDIO':
      PIN_NUMBER='(16)';
      BIDIRECTIONAL='TRUE';
      INPUT_LOAD='(-0.01,0.01)';
      OUTPUT_LOAD='(1.0,-1.0)';
    'VALRT_N':
      PIN_NUMBER='(17)';
      OUTPUT_LOAD='(1.0,-1.0)';
    'MP2':
      PIN_NUMBER='(18)';
      BIDIRECTIONAL='TRUE';
      INPUT_LOAD='(-0.01,0.01)';
      OUTPUT_LOAD='(1.0,-1.0)';
    'AVSEN':
      PIN_NUMBER='(19)';
      INPUT_LOAD='(-0.01,0.01)';
    'AVREF':
      PIN_NUMBER='(20)';
      INPUT_LOAD='(-0.01,0.01)';
    'AIREF1':
      PIN_NUMBER='(21)';
      INPUT_LOAD='(-0.01,0.01)';
    'AISEN1':
      PIN_NUMBER='(22)';
      INPUT_LOAD='(-0.01,0.01)';
    'AIREF2':
      PIN_NUMBER='(23)';
      INPUT_LOAD='(-0.01,0.01)';
    'AISEN2':
      PIN_NUMBER='(24)';
      INPUT_LOAD='(-0.01,0.01)';
    'AIREF3':
      PIN_NUMBER='(25)';
      INPUT_LOAD='(-0.01,0.01)';
    'AISEN3':
      PIN_NUMBER='(26)';
      INPUT_LOAD='(-0.01,0.01)';
    'GND':
      PIN_NUMBER='(27)';
      PINUSE='GROUND';
      NO_LOAD_CHECK='Both';
      NO_IO_CHECK='Both';
      NO_ASSERT_CHECK='TRUE';
      NO_DIR_CHECK='TRUE';
      ALLOW_CONNECT='TRUE';
    'DNC'<1>:
      PIN_NUMBER='(28)';
      PINUSE='NC';
      NO_LOAD_CHECK='Both';
      NO_IO_CHECK='Both';
      NO_ASSERT_CHECK='TRUE';
      NO_DIR_CHECK='TRUE';
      ALLOW_CONNECT='TRUE';
    'BVSEN':
      PIN_NUMBER='(29)';
      INPUT_LOAD='(-0.01,0.01)';
    'BVREF':
      PIN_NUMBER='(30)';
      INPUT_LOAD='(-0.01,0.01)';
    'BIREF1':
      PIN_NUMBER='(31)';
      INPUT_LOAD='(-0.01,0.01)';
    'BISEN1':
      PIN_NUMBER='(32)';
      INPUT_LOAD='(-0.01,0.01)';
    'XADDR2':
      PIN_NUMBER='(33)';
      INPUT_LOAD='(-0.01,0.01)';
    'BTSEN':
      PIN_NUMBER='(34)';
      INPUT_LOAD='(-0.01,0.01)';
    'ATSEN':
      PIN_NUMBER='(35)';
      INPUT_LOAD='(-0.01,0.01)';
    'XADDR1':
      PIN_NUMBER='(36)';
      INPUT_LOAD='(-0.01,0.01)';
    'VINSEN':
      PIN_NUMBER='(37)';
      INPUT_LOAD='(-0.01,0.01)';
    'IINSEN':
      PIN_NUMBER='(38)';
      INPUT_LOAD='(-0.01,0.01)';
    'VDD':
      PIN_NUMBER='(39)';
      PINUSE='POWER';
      NO_LOAD_CHECK='Both';
      NO_IO_CHECK='Both';
      NO_ASSERT_CHECK='TRUE';
      NO_DIR_CHECK='TRUE';
      ALLOW_CONNECT='TRUE';
    'VD12':
      PIN_NUMBER='(40)';
      BIDIRECTIONAL='TRUE';
      INPUT_LOAD='(-0.01,0.01)';
      OUTPUT_LOAD='(1.0,-1.0)';
    'THPAD':
      PIN_NUMBER='(41)';
      PINUSE='GROUND';
      NO_LOAD_CHECK='Both';
      NO_IO_CHECK='Both';
      NO_ASSERT_CHECK='TRUE';
      NO_DIR_CHECK='TRUE';
      ALLOW_CONNECT='TRUE';
  end_pin;
  body
    PART_NAME='PXM1310B';
    PHYS_DES_PREFIX='EU';
  end_body;
end_primitive;

END.
